# S9S_MB_2U (Grand Teton) — schematic netlist excerpt (pin names and nets, part order shuffled) for the footprints in the layout excerpt that follows; sources: Cadence DE-HDL packaged netlist, KiCad conversion of 03242023_DA0F0TMBIJ0_F0T_Motherboard_J_brd_V01_OCP.brd

PU5  ISL69260IRAZT  ISL69260IRAZ-T IC  pkg QFN40_TH_0-4_5X5XE  page 274
  PWM0  = PVCCFA_EHV_CPU0_BPWM1
  PWM1  = NC_PVCCINFAON_CPU0_APWM7
  PWM2  = NC_PVCCINFAON_CPU0_APWM6
  PWM3  = NC_PVCCINFAON_CPU0_APWM5
  PWM4  = NC_PVCCINFAON_CPU0_APWM4
  PWM5  = NC_PVCCINFAON_CPU0_APWM3
  PWM6  = PVCCINFAON_CPU0_APWM2
  PWM7  = PVCCINFAON_CPU0_APWM1
  PMSDA  = SMB_DIO_PVCCINFAON_CPU0
  PMSCL  = SMB_CLK_PVCCINFAON_CPU0
  \npmalert#\  = NC_PVCCINFAON_CPU0_SMB_ALERT
  PG0  = PWRGD_PVCCINFAON_CPU0_R
  EN0  = PVCCINFAON_CPU0_EN_R
  \nvrhot#\  = IRQ_PVCCFA_CPU0_VRHOT_N
  \npinalert#||npsyscrit#\  = PVCCINFAON_CPU0_PIN_ALERT
  PG1  = PWRGD_PVCCFA_EHV_CPU0_R
  SVCLK  = SVID_CLK_PVCCINFAON_CPU0_R
  SVDATA  = SVID_DIO_PVCCINFAON_CPU0_R
  \nsvalert#\  = SVID_ALERT_PVCCINFAON_CPU0_R
  EN1  = PVCCFA_EHV_CPU0_EN_R
  VSEN0  = SH_PVCCINFAON_CPU0_R
  RGND0  = VSENSE_PVCCINFAON_CPU0_DN
  CS7  = PVCCINFAON_CPU0_ACSP1
  CS6  = PVCCINFAON_CPU0_ACSP2
  CS5  = NC_PVCCINFAON_CPU0_ACSP3
  CS4  = NC_PVCCINFAON_CPU0_ACSP4
  CS3  = NC_PVCCINFAON_CPU0_ACSP5
  CS2  = NC_PVCCINFAON_CPU0_ACSP6
  CS1  = NC_PVCCINFAON_CPU0_ACSP7
  CS0  = PVCCFA_EHV_CPU0_BCSP1
  RGND1  = VSENSE_PVCCFA_EHV_CPU0_DN
  VSEN1  = SH_PVCCFA_EHV_CPU0_R
  CFP  = PVCCINFAON_CPU0_VR_FAULT
  ADDR_CFG  = PVCCINFAON_CPU0_ADDR
  TEMP0  = PVCCINFAON_CPU0_ATSEN
  \temp1||isys\  = PVCCFA_EHV_CPU0_BTSEN
  \vmon||iinsen||vsys||isys\  = PVCCINFAON_CPU0_CSPIN
  \vinsen||vsys\  = PVCCINFAON_CPU0_VIN_CSNIN
  VCC  = PVCCINFAON_CPU0_VCC
  VCCS  = PVCCINFAON_CPU0_VREF
  TH_GND  = GND

(kicad_pcb
	(version 20260206)
	(generator "pcbnew")
	(generator_version "10.0")
	(general
		(thickness 1.6)
		(legacy_teardrops no)
	)
	(paper "A4")
	(title_block
		(title "03242023_DA0F0TMBIJ0_F0T_Motherboard_J_brd_V01_OCP.brd")
		(comment 1 "Grand Teton / footprint 1253 of 6105 (PU5), pads 1-41 of 41")
	)
	(layers
		(0 "F.Cu" signal "TOP")
		(4 "In1.Cu" signal "GND")
		(6 "In2.Cu" signal "IN1")
		(8 "In3.Cu" signal "GND1")
		(10 "In4.Cu" signal "IN2")
		(12 "In5.Cu" signal "GND2")
		(14 "In6.Cu" signal "IN3")
		(16 "In7.Cu" signal "GND3")
		(18 "In8.Cu" signal "VCC")
		(20 "In9.Cu" signal "VCC1")
		(22 "In10.Cu" signal "GND4")
		(24 "In11.Cu" signal "IN4")
		(26 "In12.Cu" signal "GND5")
		(28 "In13.Cu" signal "IN5")
		(30 "In14.Cu" signal "GND6")
		(32 "In15.Cu" signal "IN6")
		(34 "In16.Cu" signal "GND7")
		(2 "B.Cu" signal "BOTTOM")
		(9 "F.Adhes" user "F.Adhesive")
		(11 "B.Adhes" user "B.Adhesive")
		(13 "F.Paste" user "Package Geometry/Pastemask Top")
		(15 "B.Paste" user "Package Geometry/Pastemask Bottom")
		(5 "F.SilkS" user "Ref Des/Silkscreen Top")
		(7 "B.SilkS" user "Ref Des/Silkscreen Bottom")
		(1 "F.Mask" user "Board Geometry/Soldermask Top")
		(3 "B.Mask" user "Board Geometry/Soldermask Bottom")
		(17 "Dwgs.User" user "User.Drawings")
		(19 "Cmts.User" user "User.Comments")
		(21 "Eco1.User" user "User.Eco1")
		(23 "Eco2.User" user "User.Eco2")
		(25 "Edge.Cuts" user "Board Geometry/Outline")
		(27 "Margin" user)
		(31 "F.CrtYd" user "Package Geometry/Place Bound Top")
		(29 "B.CrtYd" user "Package Geometry/Place Bound Bottom")
		(35 "F.Fab" user "Ref Des/Assembly Top")
		(33 "B.Fab" user "Ref Des/Assembly Bottom")
	)
	(footprint ""
		(layer "F.Cu")
		(at 425.705016 -136.41451 90)
		(property "Reference" "PU5"
			(at -5.203952 -1.067816 0)
			(unlocked yes)
			(layer "F.SilkS")
			(effects
				(font
					(size 0.7874 0.5842)
					(thickness 0.1524)
				)
				(justify left)
			)
		)
		(property "Value" ""
			(at 0 0 90)
			(layer "F.Fab")
			(effects
				(font
					(size 1.27 1.27)
				)
			)
		)
		(duplicate_pad_numbers_are_jumpers no)
		(pad "1" smd rect
			(at -2.400046 -1.800098)
			(size 0.1778 0.6096)
			(layers "F.Cu" "F.Mask" "F.Paste")
			(net "PVCCFA_EHV_CPU0_BPWM1")
		)
		(pad "2" smd rect
			(at -2.400046 -1.400048)
			(size 0.1778 0.6096)
			(layers "F.Cu" "F.Mask" "F.Paste")
			(net "NC_PVCCINFAON_CPU0_APWM7")
		)
		(pad "3" smd rect
			(at -2.400046 -0.999998)
			(size 0.1778 0.6096)
			(layers "F.Cu" "F.Mask" "F.Paste")
			(net "NC_PVCCINFAON_CPU0_APWM6")
		)
		(pad "4" smd rect
			(at -2.400046 -0.599948)
			(size 0.1778 0.6096)
			(layers "F.Cu" "F.Mask" "F.Paste")
			(net "NC_PVCCINFAON_CPU0_APWM5")
		)
		(pad "5" smd rect
			(at -2.400046 -0.199898)
			(size 0.1778 0.6096)
			(layers "F.Cu" "F.Mask" "F.Paste")
			(net "NC_PVCCINFAON_CPU0_APWM4")
		)
		(pad "6" smd rect
			(at -2.400046 0.199898)
			(size 0.1778 0.6096)
			(layers "F.Cu" "F.Mask" "F.Paste")
			(net "NC_PVCCINFAON_CPU0_APWM3")
		)
		(pad "7" smd rect
			(at -2.400046 0.599948)
			(size 0.1778 0.6096)
			(layers "F.Cu" "F.Mask" "F.Paste")
			(net "PVCCINFAON_CPU0_APWM2")
		)
		(pad "8" smd rect
			(at -2.400046 0.999998)
			(size 0.1778 0.6096)
			(layers "F.Cu" "F.Mask" "F.Paste")
			(net "PVCCINFAON_CPU0_APWM1")
		)
		(pad "9" smd rect
			(at -2.400046 1.400048)
			(size 0.1778 0.6096)
			(layers "F.Cu" "F.Mask" "F.Paste")
			(net "SMB_DIO_PVCCINFAON_CPU0")
		)
		(pad "10" smd rect
			(at -2.400046 1.800098)
			(size 0.1778 0.6096)
			(layers "F.Cu" "F.Mask" "F.Paste")
			(net "SMB_CLK_PVCCINFAON_CPU0")
		)
		(pad "11" smd rect
			(at -1.800098 2.400046 90)
			(size 0.1778 0.6096)
			(layers "F.Cu" "F.Mask" "F.Paste")
			(net "NC_PVCCINFAON_CPU0_SMB_ALERT")
		)
		(pad "12" smd rect
			(at -1.400048 2.400046 90)
			(size 0.1778 0.6096)
			(layers "F.Cu" "F.Mask" "F.Paste")
			(net "PWRGD_PVCCINFAON_CPU0_R")
		)
		(pad "13" smd rect
			(at -0.999998 2.400046 90)
			(size 0.1778 0.6096)
			(layers "F.Cu" "F.Mask" "F.Paste")
			(net "PVCCINFAON_CPU0_EN_R")
		)
		(pad "14" smd rect
			(at -0.599948 2.400046 90)
			(size 0.1778 0.6096)
			(layers "F.Cu" "F.Mask" "F.Paste")
			(net "IRQ_PVCCFA_CPU0_VRHOT_N")
		)
		(pad "15" smd rect
			(at -0.199898 2.400046 90)
			(size 0.1778 0.6096)
			(layers "F.Cu" "F.Mask" "F.Paste")
			(net "PVCCINFAON_CPU0_PIN_ALERT")
		)
		(pad "16" smd rect
			(at 0.199898 2.400046 90)
			(size 0.1778 0.6096)
			(layers "F.Cu" "F.Mask" "F.Paste")
			(net "PWRGD_PVCCFA_EHV_CPU0_R")
		)
		(pad "17" smd rect
			(at 0.599948 2.400046 90)
			(size 0.1778 0.6096)
			(layers "F.Cu" "F.Mask" "F.Paste")
			(net "SVID_CLK_PVCCINFAON_CPU0_R")
		)
		(pad "18" smd rect
			(at 0.999998 2.400046 90)
			(size 0.1778 0.6096)
			(layers "F.Cu" "F.Mask" "F.Paste")
			(net "SVID_DIO_PVCCINFAON_CPU0_R")
		)
		(pad "19" smd rect
			(at 1.400048 2.400046 90)
			(size 0.1778 0.6096)
			(layers "F.Cu" "F.Mask" "F.Paste")
			(net "SVID_ALERT_PVCCINFAON_CPU0_R")
		)
		(pad "20" smd rect
			(at 1.800098 2.400046 90)
			(size 0.1778 0.6096)
			(layers "F.Cu" "F.Mask" "F.Paste")
			(net "PVCCFA_EHV_CPU0_EN_R")
		)
		(pad "21" smd rect
			(at 2.400046 1.800098)
			(size 0.1778 0.6096)
			(layers "F.Cu" "F.Mask" "F.Paste")
			(net "SH_PVCCINFAON_CPU0_R")
		)
		(pad "22" smd rect
			(at 2.400046 1.400048)
			(size 0.1778 0.6096)
			(layers "F.Cu" "F.Mask" "F.Paste")
			(net "VSENSE_PVCCINFAON_CPU0_DN")
		)
		(pad "23" smd rect
			(at 2.400046 0.999998)
			(size 0.1778 0.6096)
			(layers "F.Cu" "F.Mask" "F.Paste")
			(net "PVCCINFAON_CPU0_ACSP1")
		)
		(pad "24" smd rect
			(at 2.400046 0.599948)
			(size 0.1778 0.6096)
			(layers "F.Cu" "F.Mask" "F.Paste")
			(net "PVCCINFAON_CPU0_ACSP2")
		)
		(pad "25" smd rect
			(at 2.400046 0.199898)
			(size 0.1778 0.6096)
			(layers "F.Cu" "F.Mask" "F.Paste")
			(net "NC_PVCCINFAON_CPU0_ACSP3")
		)
		(pad "26" smd rect
			(at 2.400046 -0.199898)
			(size 0.1778 0.6096)
			(layers "F.Cu" "F.Mask" "F.Paste")
			(net "NC_PVCCINFAON_CPU0_ACSP4")
		)
		(pad "27" smd rect
			(at 2.400046 -0.599948)
			(size 0.1778 0.6096)
			(layers "F.Cu" "F.Mask" "F.Paste")
			(net "NC_PVCCINFAON_CPU0_ACSP5")
		)
		(pad "28" smd rect
			(at 2.400046 -0.999998)
			(size 0.1778 0.6096)
			(layers "F.Cu" "F.Mask" "F.Paste")
			(net "NC_PVCCINFAON_CPU0_ACSP6")
		)
		(pad "29" smd rect
			(at 2.400046 -1.400048)
			(size 0.1778 0.6096)
			(layers "F.Cu" "F.Mask" "F.Paste")
			(net "NC_PVCCINFAON_CPU0_ACSP7")
		)
		(pad "30" smd rect
			(at 2.400046 -1.800098)
			(size 0.1778 0.6096)
			(layers "F.Cu" "F.Mask" "F.Paste")
			(net "PVCCFA_EHV_CPU0_BCSP1")
		)
		(pad "31" smd rect
			(at 1.800098 -2.400046 90)
			(size 0.1778 0.6096)
			(layers "F.Cu" "F.Mask" "F.Paste")
			(net "VSENSE_PVCCFA_EHV_CPU0_DN")
		)
		(pad "32" smd rect
			(at 1.400048 -2.400046 90)
			(size 0.1778 0.6096)
			(layers "F.Cu" "F.Mask" "F.Paste")
			(net "SH_PVCCFA_EHV_CPU0_R")
		)
		(pad "33" smd rect
			(at 0.999998 -2.400046 90)
			(size 0.1778 0.6096)
			(layers "F.Cu" "F.Mask" "F.Paste")
			(net "PVCCINFAON_CPU0_VR_FAULT")
		)
		(pad "34" smd rect
			(at 0.599948 -2.400046 90)
			(size 0.1778 0.6096)
			(layers "F.Cu" "F.Mask" "F.Paste")
			(net "PVCCINFAON_CPU0_ADDR")
		)
		(pad "35" smd rect
			(at 0.199898 -2.400046 90)
			(size 0.1778 0.6096)
			(layers "F.Cu" "F.Mask" "F.Paste")
			(net "PVCCINFAON_CPU0_ATSEN")
		)
		(pad "36" smd rect
			(at -0.199898 -2.400046 90)
			(size 0.1778 0.6096)
			(layers "F.Cu" "F.Mask" "F.Paste")
			(net "PVCCFA_EHV_CPU0_BTSEN")
		)
		(pad "37" smd rect
			(at -0.599948 -2.400046 90)
			(size 0.1778 0.6096)
			(layers "F.Cu" "F.Mask" "F.Paste")
			(net "PVCCINFAON_CPU0_CSPIN")
		)
		(pad "38" smd rect
			(at -0.999998 -2.400046 90)
			(size 0.1778 0.6096)
			(layers "F.Cu" "F.Mask" "F.Paste")
			(net "PVCCINFAON_CPU0_VIN_CSNIN")
		)
		(pad "39" smd rect
			(at -1.400048 -2.400046 90)
			(size 0.1778 0.6096)
			(layers "F.Cu" "F.Mask" "F.Paste")
			(net "PVCCINFAON_CPU0_VCC")
		)
		(pad "40" smd rect
			(at -1.800098 -2.400046 90)
			(size 0.1778 0.6096)
			(layers "F.Cu" "F.Mask" "F.Paste")
			(net "PVCCINFAON_CPU0_VREF")
		)
		(pad "TH" smd rect
			(at 0 0 90)
			(size 3.6576 3.6576)
			(layers "F.Cu" "F.Mask" "F.Paste")
			(net "GND")
		)
	)
)
